(kicad_pcb
	(version 20260206)
	(generator "pcbnew")
	(generator_version "10.0")
	(general
		(thickness 1.6)
		(legacy_teardrops no)
	)
	(paper "A4")
	(title_block
		(title "Bryce Canyon_F.DPB_16315-1-OCP.brd")
		(comment 1 "Bryce Canyon / footprints 2176-2182 of 2223")
	)
	(layers
		(0 "F.Cu" signal "TOP")
		(4 "In1.Cu" signal "L2GND")
		(6 "In2.Cu" signal "L3")
		(8 "In3.Cu" signal "L4GND")
		(10 "In4.Cu" signal "L5")
		(12 "In5.Cu" signal "L6VCC")
		(14 "In6.Cu" signal "L7VCC")
		(16 "In7.Cu" signal "L8")
		(18 "In8.Cu" signal "L9GND")
		(20 "In9.Cu" signal "L10")
		(22 "In10.Cu" signal "L11GND")
		(2 "B.Cu" signal "BOTTOM")
		(9 "F.Adhes" user "F.Adhesive")
		(11 "B.Adhes" user "B.Adhesive")
		(13 "F.Paste" user "Package Geometry/Pastemask Top")
		(15 "B.Paste" user "Package Geometry/Pastemask Bottom")
		(5 "F.SilkS" user "Ref Des/Silkscreen Top")
		(7 "B.SilkS" user "Ref Des/Silkscreen Bottom")
		(1 "F.Mask" user "Board Geometry/Soldermask Top")
		(3 "B.Mask" user "Board Geometry/Soldermask Bottom")
		(17 "Dwgs.User" user "User.Drawings")
		(19 "Cmts.User" user "User.Comments")
		(21 "Eco1.User" user "User.Eco1")
		(23 "Eco2.User" user "User.Eco2")
		(25 "Edge.Cuts" user "Board Geometry/Outline")
		(27 "Margin" user)
		(31 "F.CrtYd" user "Package Geometry/Place Bound Top")
		(29 "B.CrtYd" user "Package Geometry/Place Bound Bottom")
		(35 "F.Fab" user "Ref Des/Assembly Top")
		(33 "B.Fab" user "Ref Des/Assembly Bottom")
	)
	(footprint ""
		(layer "B.Cu")
		(at 220.281246 -107.461304 -90)
		(property "Reference" "TC3"
			(at 0 0 90)
			(layer "B.SilkS")
			(hide yes)
			(effects
				(font
					(size 1.27 1.27)
				)
				(justify mirror)
			)
		)
		(property "Value" "ST100U16VDM-3-GP"
			(at 0 -9.6012 270)
			(unlocked yes)
			(layer "B.Fab")
			(hide yes)
			(effects
				(font
					(size 1.016 1.016)
					(thickness 0.1524)
				)
				(justify mirror)
			)
		)
		(property "Device Type" "CT7343H79"
			(at 0 -11.1252 270)
			(unlocked yes)
			(layer "B.Fab")
			(hide yes)
			(effects
				(font
					(size 1.016 1.016)
					(thickness 0.1524)
				)
				(justify mirror)
			)
		)
		(duplicate_pad_numbers_are_jumpers no)
		(fp_line
			(start -2.286 4.8768)
			(end 2.286 4.8768)
			(stroke
				(width 0.1524)
				(type default)
			)
			(layer "B.SilkS")
		)
		(fp_line
			(start 2.286 4.8768)
			(end 2.286 2.032)
			(stroke
				(width 0.1524)
				(type default)
			)
			(layer "B.SilkS")
		)
		(fp_line
			(start -2.286 2.032)
			(end -2.286 4.8768)
			(stroke
				(width 0.1524)
				(type default)
			)
			(layer "B.SilkS")
		)
		(fp_line
			(start -2.286 -2.032)
			(end -2.286 -4.8768)
			(stroke
				(width 0.1524)
				(type default)
			)
			(layer "B.SilkS")
		)
		(fp_line
			(start -2.1082 -4.699)
			(end 2.1082 -4.699)
			(stroke
				(width 0.508)
				(type default)
			)
			(layer "B.SilkS")
		)
		(fp_line
			(start -2.286 -4.8768)
			(end 2.286 -4.8768)
			(stroke
				(width 0.1524)
				(type default)
			)
			(layer "B.SilkS")
		)
		(fp_line
			(start 2.286 -4.8768)
			(end 2.286 -2.032)
			(stroke
				(width 0.1524)
				(type default)
			)
			(layer "B.SilkS")
		)
		(fp_rect
			(start 2.1463 3.6449)
			(end -2.1463 -3.6449)
			(stroke
				(width 0)
				(type default)
			)
			(fill no)
			(layer "B.CrtYd")
		)
		(fp_poly
			(pts
				(xy 2.54 4.953) (xy 2.54 4.2926) (xy 3.81 4.2926) (xy 3.81 -4.2926) (xy 2.54 -4.2926) (xy 2.54 -4.953)
				(xy -2.54 -4.953) (xy -2.54 -4.2926) (xy -3.81 -4.2926) (xy -3.81 -1.6256) (xy -2.1463 -1.6256)
				(xy -2.1463 -3.6449) (xy 2.1463 -3.6449) (xy 2.1463 3.6449) (xy -2.1463 3.6449) (xy -2.1463 -1.6129)
				(xy -3.81 -1.6129) (xy -3.81 4.2926) (xy -2.54 4.2926) (xy -2.54 4.953)
			)
			(stroke
				(width 0)
				(type default)
			)
			(fill no)
			(layer "B.CrtYd")
		)
		(fp_rect
			(start 2.54 4.953)
			(end -2.54 -4.953)
			(stroke
				(width 0)
				(type default)
			)
			(fill no)
			(layer "B.Fab")
		)
		(fp_rect
			(start -2.54 4.2926)
			(end -3.81 -4.2926)
			(stroke
				(width 0)
				(type default)
			)
			(fill no)
			(layer "B.Fab")
		)
		(fp_rect
			(start 3.81 4.2926)
			(end 2.54 -4.2926)
			(stroke
				(width 0)
				(type default)
			)
			(fill no)
			(layer "B.Fab")
		)
		(pad "1" smd rect
			(at 0 -3.1496 90)
			(size 2.413 2.286)
			(layers "B.Cu" "B.Mask" "B.Paste")
			(net "P12V_A_COMP")
		)
		(pad "2" smd rect
			(at 0 3.1496 90)
			(size 2.413 2.286)
			(layers "B.Cu" "B.Mask" "B.Paste")
			(net "GND")
		)
		(zone
			(layer "B.Cu")
			(hatch none 0.5)
			(connect_pads
				(clearance 0)
			)
			(min_thickness 0.25)
			(keepout
				(tracks allowed)
				(vias not_allowed)
				(pads allowed)
				(copperpour not_allowed)
				(footprints allowed)
			)
			(placement
				(enabled no)
				(sheetname "")
			)
			(fill
				(thermal_gap 0.5)
				(thermal_bridge_width 0.5)
				(island_removal_mode 0)
			)
			(polygon
				(pts
					(xy 215.683846 -105.950004) (xy 215.683846 -108.972604) (xy 218.579446 -108.972604) (xy 218.909646 -108.972604)
					(xy 218.909646 -105.950004) (xy 218.579446 -105.950004)
				)
			)
		)
		(zone
			(layer "B.Cu")
			(hatch none 0.5)
			(connect_pads
				(clearance 0)
			)
			(min_thickness 0.25)
			(keepout
				(tracks allowed)
				(vias not_allowed)
				(pads allowed)
				(copperpour not_allowed)
				(footprints allowed)
			)
			(placement
				(enabled no)
				(sheetname "")
			)
			(fill
				(thermal_gap 0.5)
				(thermal_bridge_width 0.5)
				(island_removal_mode 0)
			)
			(polygon
				(pts
					(xy 221.970346 -108.972604) (xy 224.878646 -108.972604) (xy 224.878646 -105.950004) (xy 221.983046 -105.950004)
					(xy 221.652846 -105.950004) (xy 221.652846 -108.972604)
				)
			)
		)
	)
	(footprint ""
		(layer "B.Cu")
		(at 192.180972 -228.396292 180)
		(property "Reference" "C672"
			(at 0 0 0)
			(layer "B.SilkS")
			(hide yes)
			(effects
				(font
					(size 1.27 1.27)
				)
				(justify mirror)
			)
		)
		(property "Value" "SC10U16V5KX-7-GP-U"
			(at 0.0762 -6.1214 180)
			(unlocked yes)
			(layer "B.Fab")
			(hide yes)
			(effects
				(font
					(size 1.016 1.016)
					(thickness 0.1524)
				)
				(justify mirror)
			)
		)
		(property "Device Type" "C805H58"
			(at 0.0762 -8.1534 180)
			(unlocked yes)
			(layer "B.Fab")
			(hide yes)
			(effects
				(font
					(size 1.016 1.016)
					(thickness 0.1524)
				)
				(justify mirror)
			)
		)
		(duplicate_pad_numbers_are_jumpers no)
		(fp_line
			(start -0.635 0)
			(end 0.635 0)
			(stroke
				(width 0.508)
				(type default)
			)
			(layer "B.SilkS")
		)
		(fp_rect
			(start 0.9652 1.778)
			(end -0.9652 -1.778)
			(stroke
				(width 0)
				(type default)
			)
			(fill no)
			(layer "B.CrtYd")
		)
		(fp_poly
			(pts
				(xy 0.9652 -1.778) (xy -0.9652 -1.778) (xy -0.9652 1.778) (xy 0.9652 1.778)
			)
			(stroke
				(width 0)
				(type default)
			)
			(fill no)
			(layer "B.Fab")
		)
		(pad "1" smd rect
			(at 0 -0.9652)
			(size 1.397 1.143)
			(layers "B.Cu" "B.Mask" "B.Paste")
			(net "P3V3_STBY_VIN")
		)
		(pad "2" smd rect
			(at 0 0.9652)
			(size 1.397 1.143)
			(layers "B.Cu" "B.Mask" "B.Paste")
			(net "GND")
		)
	)
	(footprint ""
		(layer "B.Cu")
		(at 470.408 -237.363 -90)
		(property "Reference" "C653"
			(at 0 0 90)
			(layer "B.SilkS")
			(hide yes)
			(effects
				(font
					(size 1.27 1.27)
				)
				(justify mirror)
			)
		)
		(property "Value" "SC10U16V5KX-7-GP-U"
			(at 0.0762 -6.1214 270)
			(unlocked yes)
			(layer "B.Fab")
			(hide yes)
			(effects
				(font
					(size 1.016 1.016)
					(thickness 0.1524)
				)
				(justify mirror)
			)
		)
		(property "Device Type" "C805H58"
			(at 0.0762 -8.1534 270)
			(unlocked yes)
			(layer "B.Fab")
			(hide yes)
			(effects
				(font
					(size 1.016 1.016)
					(thickness 0.1524)
				)
				(justify mirror)
			)
		)
		(duplicate_pad_numbers_are_jumpers no)
		(fp_line
			(start -0.635 0)
			(end 0.635 0)
			(stroke
				(width 0.508)
				(type default)
			)
			(layer "B.SilkS")
		)
		(fp_rect
			(start 0.9652 1.778)
			(end -0.9652 -1.778)
			(stroke
				(width 0)
				(type default)
			)
			(fill no)
			(layer "B.CrtYd")
		)
		(fp_poly
			(pts
				(xy 0.9652 -1.778) (xy -0.9652 -1.778) (xy -0.9652 1.778) (xy 0.9652 1.778)
			)
			(stroke
				(width 0)
				(type default)
			)
			(fill no)
			(layer "B.Fab")
		)
		(pad "1" smd rect
			(at 0 -0.9652 90)
			(size 1.397 1.143)
			(layers "B.Cu" "B.Mask" "B.Paste")
			(net "P12V_A_VIN_U27")
		)
		(pad "2" smd rect
			(at 0 0.9652 90)
			(size 1.397 1.143)
			(layers "B.Cu" "B.Mask" "B.Paste")
			(net "GND")
		)
	)
	(footprint ""
		(layer "B.Cu")
		(at 55.818024 -150.063454 -90)
		(property "Reference" "C626"
			(at 0 0 90)
			(layer "B.SilkS")
			(hide yes)
			(effects
				(font
					(size 1.27 1.27)
				)
				(justify mirror)
			)
		)
		(property "Value" "SC470P50V2KX-3GP"
			(at -1.1811 -2.7051 270)
			(unlocked yes)
			(layer "B.Fab")
			(hide yes)
			(effects
				(font
					(size 1.016 1.016)
					(thickness 0.1524)
				)
				(justify mirror)
			)
		)
		(property "Device Type" "C402H22"
			(at -1.1811 -4.2291 270)
			(unlocked yes)
			(layer "B.Fab")
			(hide yes)
			(effects
				(font
					(size 1.016 1.016)
					(thickness 0.1524)
				)
				(justify mirror)
			)
		)
		(duplicate_pad_numbers_are_jumpers no)
		(fp_rect
			(start 0.4318 0.9525)
			(end -0.4318 -0.9525)
			(stroke
				(width 0)
				(type default)
			)
			(fill no)
			(layer "B.CrtYd")
		)
		(fp_rect
			(start 0.4318 0.9525)
			(end -0.4318 -0.9525)
			(stroke
				(width 0)
				(type default)
			)
			(fill no)
			(layer "B.Fab")
		)
		(pad "1" smd custom
			(at 0 -0.4445 90)
			(size 0.1524 0.1524)
			(layers "B.Cu" "B.Mask" "B.Paste")
			(net "P5V_B_LL_R")
			(options
				(clearance outline)
				(anchor circle)
			)
			(primitives
				(gr_poly
					(pts
						(arc
							(start 0.3048 0.2032)
							(mid 0.275042 0.275042)
							(end 0.2032 0.3048)
						)
						(arc
							(start -0.2032 0.3048)
							(mid -0.275042 0.275042)
							(end -0.3048 0.2032)
						)
						(arc
							(start -0.3048 -0.2032)
							(mid -0.275042 -0.275042)
							(end -0.2032 -0.3048)
						)
						(arc
							(start 0.2032 -0.3048)
							(mid 0.275042 -0.275042)
							(end 0.3048 -0.2032)
						)
					)
					(width 0)
					(fill yes)
				)
			)
		)
		(pad "2" smd custom
			(at 0 0.4445 90)
			(size 0.1524 0.1524)
			(layers "B.Cu" "B.Mask" "B.Paste")
			(net "P5V_B_VFB")
			(options
				(clearance outline)
				(anchor circle)
			)
			(primitives
				(gr_poly
					(pts
						(arc
							(start 0.3048 0.2032)
							(mid 0.275042 0.275042)
							(end 0.2032 0.3048)
						)
						(arc
							(start -0.2032 0.3048)
							(mid -0.275042 0.275042)
							(end -0.3048 0.2032)
						)
						(arc
							(start -0.3048 -0.2032)
							(mid -0.275042 -0.275042)
							(end -0.2032 -0.3048)
						)
						(arc
							(start 0.2032 -0.3048)
							(mid 0.275042 -0.275042)
							(end 0.3048 -0.2032)
						)
					)
					(width 0)
					(fill yes)
				)
			)
		)
	)
	(footprint ""
		(layer "B.Cu")
		(at 482.219 -238.252 90)
		(property "Reference" "R1270"
			(at 0 0 90)
			(layer "B.SilkS")
			(hide yes)
			(effects
				(font
					(size 1.27 1.27)
				)
				(justify mirror)
			)
		)
		(property "Value" "200KR2F-L-GP"
			(at -0.064008 -3.993896 90)
			(unlocked yes)
			(layer "B.Fab")
			(hide yes)
			(effects
				(font
					(size 1.016 1.016)
					(thickness 0.1524)
				)
				(justify mirror)
			)
		)
		(property "Device Type" "R402H16"
			(at -0.064008 -5.517896 90)
			(unlocked yes)
			(layer "B.Fab")
			(hide yes)
			(effects
				(font
					(size 1.016 1.016)
					(thickness 0.1524)
				)
				(justify mirror)
			)
		)
		(duplicate_pad_numbers_are_jumpers no)
		(fp_line
			(start 0.508 -0.9398)
			(end 0.508 0.9398)
			(stroke
				(width 0.1524)
				(type default)
			)
			(layer "B.SilkS")
		)
		(fp_line
			(start -0.508 -0.9398)
			(end 0.508 -0.9398)
			(stroke
				(width 0.1524)
				(type default)
			)
			(layer "B.SilkS")
		)
		(fp_rect
			(start 0.508 0.9398)
			(end -0.508 -0.9398)
			(stroke
				(width 0)
				(type default)
			)
			(fill no)
			(layer "B.CrtYd")
		)
		(fp_rect
			(start 0.508 0.9398)
			(end -0.508 -0.9398)
			(stroke
				(width 0)
				(type default)
			)
			(fill no)
			(layer "B.Fab")
		)
		(pad "1" smd custom
			(at 0 -0.4445 270)
			(size 0.1397 0.1397)
			(layers "B.Cu" "B.Mask" "B.Paste")
			(net "P5V_D_MODE")
			(options
				(clearance outline)
				(anchor circle)
			)
			(primitives
				(gr_poly
					(pts
						(arc
							(start -0.1778 0.2794)
							(mid -0.249642 0.249642)
							(end -0.2794 0.1778)
						)
						(arc
							(start -0.2794 -0.1778)
							(mid -0.249642 -0.249642)
							(end -0.1778 -0.2794)
						)
						(arc
							(start 0.1778 -0.2794)
							(mid 0.249642 -0.249642)
							(end 0.2794 -0.1778)
						)
						(arc
							(start 0.2794 0.1778)
							(mid 0.249642 0.249642)
							(end 0.1778 0.2794)
						)
					)
					(width 0)
					(fill yes)
				)
			)
		)
		(pad "2" smd custom
			(at 0 0.4445 270)
			(size 0.1397 0.1397)
			(layers "B.Cu" "B.Mask" "B.Paste")
			(net "P5V_A_4_PGOOD")
			(options
				(clearance outline)
				(anchor circle)
			)
			(primitives
				(gr_poly
					(pts
						(arc
							(start -0.1778 0.2794)
							(mid -0.249642 0.249642)
							(end -0.2794 0.1778)
						)
						(arc
							(start -0.2794 -0.1778)
							(mid -0.249642 -0.249642)
							(end -0.1778 -0.2794)
						)
						(arc
							(start 0.1778 -0.2794)
							(mid 0.249642 -0.249642)
							(end 0.2794 -0.1778)
						)
						(arc
							(start 0.2794 0.1778)
							(mid 0.249642 0.249642)
							(end 0.1778 0.2794)
						)
					)
					(width 0)
					(fill yes)
				)
			)
		)
	)
	(footprint ""
		(layer "B.Cu")
		(at 455.893424 -257.759454 -90)
		(property "Reference" "C643"
			(at 0 0 90)
			(layer "B.SilkS")
			(hide yes)
			(effects
				(font
					(size 1.27 1.27)
				)
				(justify mirror)
			)
		)
		(property "Value" "SC470P50V2KX-3GP"
			(at -1.1811 -2.7051 270)
			(unlocked yes)
			(layer "B.Fab")
			(hide yes)
			(effects
				(font
					(size 1.016 1.016)
					(thickness 0.1524)
				)
				(justify mirror)
			)
		)
		(property "Device Type" "C402H22"
			(at -1.1811 -4.2291 270)
			(unlocked yes)
			(layer "B.Fab")
			(hide yes)
			(effects
				(font
					(size 1.016 1.016)
					(thickness 0.1524)
				)
				(justify mirror)
			)
		)
		(duplicate_pad_numbers_are_jumpers no)
		(fp_rect
			(start 0.4318 0.9525)
			(end -0.4318 -0.9525)
			(stroke
				(width 0)
				(type default)
			)
			(fill no)
			(layer "B.CrtYd")
		)
		(fp_rect
			(start 0.4318 0.9525)
			(end -0.4318 -0.9525)
			(stroke
				(width 0)
				(type default)
			)
			(fill no)
			(layer "B.Fab")
		)
		(pad "1" smd custom
			(at 0 -0.4445 90)
			(size 0.1524 0.1524)
			(layers "B.Cu" "B.Mask" "B.Paste")
			(net "P5V_C_LL_R")
			(options
				(clearance outline)
				(anchor circle)
			)
			(primitives
				(gr_poly
					(pts
						(arc
							(start 0.3048 0.2032)
							(mid 0.275042 0.275042)
							(end 0.2032 0.3048)
						)
						(arc
							(start -0.2032 0.3048)
							(mid -0.275042 0.275042)
							(end -0.3048 0.2032)
						)
						(arc
							(start -0.3048 -0.2032)
							(mid -0.275042 -0.275042)
							(end -0.2032 -0.3048)
						)
						(arc
							(start 0.2032 -0.3048)
							(mid 0.275042 -0.275042)
							(end 0.3048 -0.2032)
						)
					)
					(width 0)
					(fill yes)
				)
			)
		)
		(pad "2" smd custom
			(at 0 0.4445 90)
			(size 0.1524 0.1524)
			(layers "B.Cu" "B.Mask" "B.Paste")
			(net "P5V_C_VFB")
			(options
				(clearance outline)
				(anchor circle)
			)
			(primitives
				(gr_poly
					(pts
						(arc
							(start 0.3048 0.2032)
							(mid 0.275042 0.275042)
							(end 0.2032 0.3048)
						)
						(arc
							(start -0.2032 0.3048)
							(mid -0.275042 0.275042)
							(end -0.3048 0.2032)
						)
						(arc
							(start -0.3048 -0.2032)
							(mid -0.275042 -0.275042)
							(end -0.2032 -0.3048)
						)
						(arc
							(start 0.2032 -0.3048)
							(mid 0.275042 -0.275042)
							(end 0.3048 -0.2032)
						)
					)
					(width 0)
					(fill yes)
				)
			)
		)
	)
	(footprint ""
		(layer "B.Cu")
		(at 56.134 -252.1966 180)
		(property "Reference" "C611"
			(at 0 0 0)
			(layer "B.SilkS")
			(hide yes)
			(effects
				(font
					(size 1.27 1.27)
				)
				(justify mirror)
			)
		)
		(property "Value" "SC10U16V5KX-7-GP-U"
			(at 0.0762 -6.1214 180)
			(unlocked yes)
			(layer "B.Fab")
			(hide yes)
			(effects
				(font
					(size 1.016 1.016)
					(thickness 0.1524)
				)
				(justify mirror)
			)
		)
		(property "Device Type" "C805H58"
			(at 0.0762 -8.1534 180)
			(unlocked yes)
			(layer "B.Fab")
			(hide yes)
			(effects
				(font
					(size 1.016 1.016)
					(thickness 0.1524)
				)
				(justify mirror)
			)
		)
		(duplicate_pad_numbers_are_jumpers no)
		(fp_line
			(start -0.635 0)
			(end 0.635 0)
			(stroke
				(width 0.508)
				(type default)
			)
			(layer "B.SilkS")
		)
		(fp_rect
			(start 0.9652 1.778)
			(end -0.9652 -1.778)
			(stroke
				(width 0)
				(type default)
			)
			(fill no)
			(layer "B.CrtYd")
		)
		(fp_poly
			(pts
				(xy 0.9652 -1.778) (xy -0.9652 -1.778) (xy -0.9652 1.778) (xy 0.9652 1.778)
			)
			(stroke
				(width 0)
				(type default)
			)
			(fill no)
			(layer "B.Fab")
		)
		(pad "1" smd rect
			(at 0 -0.9652)
			(size 1.397 1.143)
			(layers "B.Cu" "B.Mask" "B.Paste")
			(net "P5V_A_1")
		)
		(pad "2" smd rect
			(at 0 0.9652)
			(size 1.397 1.143)
			(layers "B.Cu" "B.Mask" "B.Paste")
			(net "GND")
		)
	)
)
